(kicad_pcb
	(version 20260206)
	(generator "pcbnew")
	(generator_version "10.0")
	(general
		(thickness 1.6)
		(legacy_teardrops no)
	)
	(paper "A4")
	(title_block
		(title "Bryce Canyon_IOM_IOC_16318-2_OCP.brd")
		(comment 1 "Bryce Canyon / footprints 1289-1297 of 1605")
	)
	(layers
		(0 "F.Cu" signal "TOP")
		(4 "In1.Cu" signal "L2GND")
		(6 "In2.Cu" signal "L3")
		(8 "In3.Cu" signal "L4VCC")
		(10 "In4.Cu" signal "L5VCC")
		(12 "In5.Cu" signal "L6")
		(14 "In6.Cu" signal "L7GND")
		(2 "B.Cu" signal "BOTTOM")
		(9 "F.Adhes" user "F.Adhesive")
		(11 "B.Adhes" user "B.Adhesive")
		(13 "F.Paste" user "Package Geometry/Pastemask Top")
		(15 "B.Paste" user "Package Geometry/Pastemask Bottom")
		(5 "F.SilkS" user "Ref Des/Silkscreen Top")
		(7 "B.SilkS" user "Ref Des/Silkscreen Bottom")
		(1 "F.Mask" user "Board Geometry/Soldermask Top")
		(3 "B.Mask" user "Board Geometry/Soldermask Bottom")
		(17 "Dwgs.User" user "User.Drawings")
		(19 "Cmts.User" user "User.Comments")
		(21 "Eco1.User" user "User.Eco1")
		(23 "Eco2.User" user "User.Eco2")
		(25 "Edge.Cuts" user "Board Geometry/Outline")
		(27 "Margin" user)
		(31 "F.CrtYd" user "Package Geometry/Place Bound Top")
		(29 "B.CrtYd" user "Package Geometry/Place Bound Bottom")
		(35 "F.Fab" user "Ref Des/Assembly Top")
		(33 "B.Fab" user "Ref Des/Assembly Bottom")
	)
	(footprint ""
		(layer "B.Cu")
		(at 209.042 -62.0268 -90)
		(property "Reference" "R637"
			(at 0 0 90)
			(layer "B.SilkS")
			(hide yes)
			(effects
				(font
					(size 1.27 1.27)
				)
				(justify mirror)
			)
		)
		(property "Value" "4K7R2F-GP"
			(at -0.064008 -3.993896 270)
			(unlocked yes)
			(layer "B.Fab")
			(hide yes)
			(effects
				(font
					(size 1.016 1.016)
					(thickness 0.1524)
				)
				(justify mirror)
			)
		)
		(property "Device Type" "R402H16"
			(at -0.064008 -5.517896 270)
			(unlocked yes)
			(layer "B.Fab")
			(hide yes)
			(effects
				(font
					(size 1.016 1.016)
					(thickness 0.1524)
				)
				(justify mirror)
			)
		)
		(duplicate_pad_numbers_are_jumpers no)
		(fp_line
			(start -0.508 -0.9398)
			(end 0.508 -0.9398)
			(stroke
				(width 0.1524)
				(type default)
			)
			(layer "B.SilkS")
		)
		(fp_line
			(start 0.508 -0.9398)
			(end 0.508 0.9398)
			(stroke
				(width 0.1524)
				(type default)
			)
			(layer "B.SilkS")
		)
		(fp_rect
			(start 0.508 0.9398)
			(end -0.508 -0.9398)
			(stroke
				(width 0)
				(type default)
			)
			(fill no)
			(layer "B.CrtYd")
		)
		(fp_rect
			(start 0.508 0.9398)
			(end -0.508 -0.9398)
			(stroke
				(width 0)
				(type default)
			)
			(fill no)
			(layer "B.Fab")
		)
		(pad "1" smd custom
			(at 0 -0.4445 90)
			(size 0.1397 0.1397)
			(layers "B.Cu" "B.Mask" "B.Paste")
			(net "P1V8")
			(options
				(clearance outline)
				(anchor circle)
			)
			(primitives
				(gr_poly
					(pts
						(arc
							(start -0.1778 0.2794)
							(mid -0.249642 0.249642)
							(end -0.2794 0.1778)
						)
						(arc
							(start -0.2794 -0.1778)
							(mid -0.249642 -0.249642)
							(end -0.1778 -0.2794)
						)
						(arc
							(start 0.1778 -0.2794)
							(mid 0.249642 -0.249642)
							(end 0.2794 -0.1778)
						)
						(arc
							(start 0.2794 0.1778)
							(mid 0.249642 0.249642)
							(end 0.1778 0.2794)
						)
					)
					(width 0)
					(fill yes)
				)
			)
		)
		(pad "2" smd custom
			(at 0 0.4445 90)
			(size 0.1397 0.1397)
			(layers "B.Cu" "B.Mask" "B.Paste")
			(net "ICE_SEL")
			(options
				(clearance outline)
				(anchor circle)
			)
			(primitives
				(gr_poly
					(pts
						(arc
							(start -0.1778 0.2794)
							(mid -0.249642 0.249642)
							(end -0.2794 0.1778)
						)
						(arc
							(start -0.2794 -0.1778)
							(mid -0.249642 -0.249642)
							(end -0.1778 -0.2794)
						)
						(arc
							(start 0.1778 -0.2794)
							(mid 0.249642 -0.249642)
							(end 0.2794 -0.1778)
						)
						(arc
							(start 0.2794 0.1778)
							(mid 0.249642 0.249642)
							(end 0.1778 0.2794)
						)
					)
					(width 0)
					(fill yes)
				)
			)
		)
	)
	(footprint ""
		(layer "B.Cu")
		(at 198.52132 -66.25336)
		(property "Reference" "C375"
			(at 0 0 0)
			(layer "B.SilkS")
			(hide yes)
			(effects
				(font
					(size 1.27 1.27)
				)
				(justify mirror)
			)
		)
		(property "Value" "SC1U6D3V1MX-GP"
			(at -1.9177 2.0193 0)
			(unlocked yes)
			(layer "B.Fab")
			(hide yes)
			(effects
				(font
					(size 1.016 1.016)
					(thickness 0.1524)
				)
				(justify mirror)
			)
		)
		(property "Device Type" "C0201H14"
			(at -1.9177 0.4953 0)
			(unlocked yes)
			(layer "B.Fab")
			(hide yes)
			(effects
				(font
					(size 1.016 1.016)
					(thickness 0.1524)
				)
				(justify mirror)
			)
		)
		(duplicate_pad_numbers_are_jumpers no)
		(fp_rect
			(start 0.1524 0.3048)
			(end -0.1524 -0.3048)
			(stroke
				(width 0)
				(type default)
			)
			(fill no)
			(layer "B.CrtYd")
		)
		(fp_poly
			(pts
				(xy 0.2794 0.6477) (xy 0.2794 -0.6477) (xy -0.2794 -0.6477) (xy -0.2794 -0.1905) (xy -0.1524 -0.1905)
				(xy -0.1524 -0.3048) (xy 0.1524 -0.3048) (xy 0.1524 0.3048) (xy -0.1524 0.3048) (xy -0.1524 -0.1778)
				(xy -0.2794 -0.1778) (xy -0.2794 0.6477)
			)
			(stroke
				(width 0)
				(type default)
			)
			(fill no)
			(layer "B.CrtYd")
		)
		(fp_rect
			(start 0.2794 0.6477)
			(end -0.2794 -0.6477)
			(stroke
				(width 0)
				(type default)
			)
			(fill no)
			(layer "B.Fab")
		)
		(pad "1" smd custom
			(at 0 -0.2794 180)
			(size 0.0762 0.0762)
			(layers "B.Cu" "B.Mask" "B.Paste")
			(net "SAS0_AVDD")
			(options
				(clearance outline)
				(anchor circle)
			)
			(primitives
				(gr_poly
					(pts
						(arc
							(start 0.1524 0.127)
							(mid 0.137521 0.162921)
							(end 0.1016 0.1778)
						)
						(arc
							(start -0.1016 0.1778)
							(mid -0.137521 0.162921)
							(end -0.1524 0.127)
						)
						(arc
							(start -0.1524 -0.127)
							(mid -0.137521 -0.162921)
							(end -0.1016 -0.1778)
						)
						(arc
							(start 0.1016 -0.1778)
							(mid 0.137521 -0.162921)
							(end 0.1524 -0.127)
						)
					)
					(width 0)
					(fill yes)
				)
			)
		)
		(pad "2" smd custom
			(at 0 0.2794 180)
			(size 0.0762 0.0762)
			(layers "B.Cu" "B.Mask" "B.Paste")
			(net "GND")
			(options
				(clearance outline)
				(anchor circle)
			)
			(primitives
				(gr_poly
					(pts
						(arc
							(start 0.1524 0.127)
							(mid 0.137521 0.162921)
							(end 0.1016 0.1778)
						)
						(arc
							(start -0.1016 0.1778)
							(mid -0.137521 0.162921)
							(end -0.1524 0.127)
						)
						(arc
							(start -0.1524 -0.127)
							(mid -0.137521 -0.162921)
							(end -0.1016 -0.1778)
						)
						(arc
							(start 0.1016 -0.1778)
							(mid 0.137521 -0.162921)
							(end 0.1524 -0.127)
						)
					)
					(width 0)
					(fill yes)
				)
			)
		)
	)
	(footprint ""
		(layer "B.Cu")
		(at 202.112626 -54.946296)
		(property "Reference" "C442"
			(at 0 0 0)
			(layer "B.SilkS")
			(hide yes)
			(effects
				(font
					(size 1.27 1.27)
				)
				(justify mirror)
			)
		)
		(property "Value" "SCD1U16V2KX-3GP"
			(at -1.1811 -2.7051 0)
			(unlocked yes)
			(layer "B.Fab")
			(hide yes)
			(effects
				(font
					(size 1.016 1.016)
					(thickness 0.1524)
				)
				(justify mirror)
			)
		)
		(property "Device Type" "C402H22"
			(at -1.1811 -4.2291 0)
			(unlocked yes)
			(layer "B.Fab")
			(hide yes)
			(effects
				(font
					(size 1.016 1.016)
					(thickness 0.1524)
				)
				(justify mirror)
			)
		)
		(duplicate_pad_numbers_are_jumpers no)
		(fp_rect
			(start 0.4318 0.9525)
			(end -0.4318 -0.9525)
			(stroke
				(width 0)
				(type default)
			)
			(fill no)
			(layer "B.CrtYd")
		)
		(fp_rect
			(start 0.4318 0.9525)
			(end -0.4318 -0.9525)
			(stroke
				(width 0)
				(type default)
			)
			(fill no)
			(layer "B.Fab")
		)
		(pad "1" smd custom
			(at 0 -0.4445 180)
			(size 0.1524 0.1524)
			(layers "B.Cu" "B.Mask" "B.Paste")
			(net "P1V8")
			(options
				(clearance outline)
				(anchor circle)
			)
			(primitives
				(gr_poly
					(pts
						(arc
							(start 0.3048 0.2032)
							(mid 0.275042 0.275042)
							(end 0.2032 0.3048)
						)
						(arc
							(start -0.2032 0.3048)
							(mid -0.275042 0.275042)
							(end -0.3048 0.2032)
						)
						(arc
							(start -0.3048 -0.2032)
							(mid -0.275042 -0.275042)
							(end -0.2032 -0.3048)
						)
						(arc
							(start 0.2032 -0.3048)
							(mid 0.275042 -0.275042)
							(end 0.3048 -0.2032)
						)
					)
					(width 0)
					(fill yes)
				)
			)
		)
		(pad "2" smd custom
			(at 0 0.4445 180)
			(size 0.1524 0.1524)
			(layers "B.Cu" "B.Mask" "B.Paste")
			(net "GND")
			(options
				(clearance outline)
				(anchor circle)
			)
			(primitives
				(gr_poly
					(pts
						(arc
							(start 0.3048 0.2032)
							(mid 0.275042 0.275042)
							(end 0.2032 0.3048)
						)
						(arc
							(start -0.2032 0.3048)
							(mid -0.275042 0.275042)
							(end -0.3048 0.2032)
						)
						(arc
							(start -0.3048 -0.2032)
							(mid -0.275042 -0.275042)
							(end -0.2032 -0.3048)
						)
						(arc
							(start 0.2032 -0.3048)
							(mid 0.275042 -0.275042)
							(end 0.3048 -0.2032)
						)
					)
					(width 0)
					(fill yes)
				)
			)
		)
	)
	(footprint ""
		(layer "B.Cu")
		(at 56.376824 -138.325098 -90)
		(property "Reference" "TP70"
			(at 0 0 90)
			(layer "B.SilkS")
			(hide yes)
			(effects
				(font
					(size 1.27 1.27)
				)
				(justify mirror)
			)
		)
		(property "Value" "TPAD28-2-GP"
			(at 0.0127 -1.6637 270)
			(unlocked yes)
			(layer "B.Fab")
			(hide yes)
			(effects
				(font
					(size 1.016 1.016)
					(thickness 0.1524)
				)
				(justify mirror)
			)
		)
		(property "Device Type" "TPAD28"
			(at 0.0127 -3.1877 270)
			(unlocked yes)
			(layer "B.Fab")
			(hide yes)
			(effects
				(font
					(size 1.016 1.016)
					(thickness 0.1524)
				)
				(justify mirror)
			)
		)
		(duplicate_pad_numbers_are_jumpers no)
		(fp_poly
			(pts
				(arc
					(start 0 -0.3556)
					(mid 0 0.3556)
					(end 0 -0.3556)
				)
			)
			(stroke
				(width 0)
				(type default)
			)
			(fill no)
			(layer "B.CrtYd")
		)
		(fp_poly
			(pts
				(arc
					(start 0 -0.6096)
					(mid 0 0.6096)
					(end 0 -0.6096)
				)
			)
			(stroke
				(width 0)
				(type default)
			)
			(fill no)
			(layer "B.Fab")
		)
		(pad "1" smd circle
			(at 0 0 90)
			(size 0.7112 0.7112)
			(layers "B.Cu" "B.Mask" "B.Paste")
			(net "TP_BMC_GPIOI0")
		)
	)
	(footprint ""
		(layer "B.Cu")
		(at 186.173872 -74.793856 -90)
		(property "Reference" "C471"
			(at 0 0 90)
			(layer "B.SilkS")
			(hide yes)
			(effects
				(font
					(size 1.27 1.27)
				)
				(justify mirror)
			)
		)
		(property "Value" "SCD1U16V2KX-3GP"
			(at -1.1811 -2.7051 270)
			(unlocked yes)
			(layer "B.Fab")
			(hide yes)
			(effects
				(font
					(size 1.016 1.016)
					(thickness 0.1524)
				)
				(justify mirror)
			)
		)
		(property "Device Type" "C402H22"
			(at -1.1811 -4.2291 270)
			(unlocked yes)
			(layer "B.Fab")
			(hide yes)
			(effects
				(font
					(size 1.016 1.016)
					(thickness 0.1524)
				)
				(justify mirror)
			)
		)
		(duplicate_pad_numbers_are_jumpers no)
		(fp_rect
			(start 0.4318 0.9525)
			(end -0.4318 -0.9525)
			(stroke
				(width 0)
				(type default)
			)
			(fill no)
			(layer "B.CrtYd")
		)
		(fp_rect
			(start 0.4318 0.9525)
			(end -0.4318 -0.9525)
			(stroke
				(width 0)
				(type default)
			)
			(fill no)
			(layer "B.Fab")
		)
		(pad "1" smd custom
			(at 0 -0.4445 90)
			(size 0.1524 0.1524)
			(layers "B.Cu" "B.Mask" "B.Paste")
			(net "P1V8")
			(options
				(clearance outline)
				(anchor circle)
			)
			(primitives
				(gr_poly
					(pts
						(arc
							(start 0.3048 0.2032)
							(mid 0.275042 0.275042)
							(end 0.2032 0.3048)
						)
						(arc
							(start -0.2032 0.3048)
							(mid -0.275042 0.275042)
							(end -0.3048 0.2032)
						)
						(arc
							(start -0.3048 -0.2032)
							(mid -0.275042 -0.275042)
							(end -0.2032 -0.3048)
						)
						(arc
							(start 0.2032 -0.3048)
							(mid 0.275042 -0.275042)
							(end 0.3048 -0.2032)
						)
					)
					(width 0)
					(fill yes)
				)
			)
		)
		(pad "2" smd custom
			(at 0 0.4445 90)
			(size 0.1524 0.1524)
			(layers "B.Cu" "B.Mask" "B.Paste")
			(net "GND")
			(options
				(clearance outline)
				(anchor circle)
			)
			(primitives
				(gr_poly
					(pts
						(arc
							(start 0.3048 0.2032)
							(mid 0.275042 0.275042)
							(end 0.2032 0.3048)
						)
						(arc
							(start -0.2032 0.3048)
							(mid -0.275042 0.275042)
							(end -0.3048 0.2032)
						)
						(arc
							(start -0.3048 -0.2032)
							(mid -0.275042 -0.275042)
							(end -0.2032 -0.3048)
						)
						(arc
							(start 0.2032 -0.3048)
							(mid 0.275042 -0.275042)
							(end 0.3048 -0.2032)
						)
					)
					(width 0)
					(fill yes)
				)
			)
		)
	)
	(footprint ""
		(layer "B.Cu")
		(at 189.21984 -50.14722)
		(property "Reference" "TP169"
			(at 0 0 0)
			(layer "B.SilkS")
			(hide yes)
			(effects
				(font
					(size 1.27 1.27)
				)
				(justify mirror)
			)
		)
		(property "Value" "TPAD28-2-GP"
			(at 0.0127 -1.6637 0)
			(unlocked yes)
			(layer "B.Fab")
			(hide yes)
			(effects
				(font
					(size 1.016 1.016)
					(thickness 0.1524)
				)
				(justify mirror)
			)
		)
		(property "Device Type" "TPAD28"
			(at 0.0127 -3.1877 0)
			(unlocked yes)
			(layer "B.Fab")
			(hide yes)
			(effects
				(font
					(size 1.016 1.016)
					(thickness 0.1524)
				)
				(justify mirror)
			)
		)
		(duplicate_pad_numbers_are_jumpers no)
		(fp_poly
			(pts
				(arc
					(start 0.3556 0)
					(mid -0.3556 0)
					(end 0.3556 0)
				)
			)
			(stroke
				(width 0)
				(type default)
			)
			(fill no)
			(layer "B.CrtYd")
		)
		(fp_poly
			(pts
				(arc
					(start 0.6096 0)
					(mid -0.6096 0)
					(end 0.6096 0)
				)
			)
			(stroke
				(width 0)
				(type default)
			)
			(fill no)
			(layer "B.Fab")
		)
		(pad "1" smd circle
			(at 0 0 180)
			(size 0.7112 0.7112)
			(layers "B.Cu" "B.Mask" "B.Paste")
			(net "VDDIO_15")
		)
	)
	(footprint ""
		(layer "B.Cu")
		(at 47.22368 -155.25496 90)
		(property "Reference" "C91"
			(at 0 0 90)
			(layer "B.SilkS")
			(hide yes)
			(effects
				(font
					(size 1.27 1.27)
				)
				(justify mirror)
			)
		)
		(property "Value" "SC100P50V2JN-3GP"
			(at -1.1811 -2.7051 90)
			(unlocked yes)
			(layer "B.Fab")
			(hide yes)
			(effects
				(font
					(size 1.016 1.016)
					(thickness 0.1524)
				)
				(justify mirror)
			)
		)
		(property "Device Type" "C402H22"
			(at -1.1811 -4.2291 90)
			(unlocked yes)
			(layer "B.Fab")
			(hide yes)
			(effects
				(font
					(size 1.016 1.016)
					(thickness 0.1524)
				)
				(justify mirror)
			)
		)
		(duplicate_pad_numbers_are_jumpers no)
		(fp_rect
			(start 0.4318 0.9525)
			(end -0.4318 -0.9525)
			(stroke
				(width 0)
				(type default)
			)
			(fill no)
			(layer "B.CrtYd")
		)
		(fp_rect
			(start 0.4318 0.9525)
			(end -0.4318 -0.9525)
			(stroke
				(width 0)
				(type default)
			)
			(fill no)
			(layer "B.Fab")
		)
		(pad "1" smd custom
			(at 0 -0.4445 270)
			(size 0.1524 0.1524)
			(layers "B.Cu" "B.Mask" "B.Paste")
			(net "DACAV33")
			(options
				(clearance outline)
				(anchor circle)
			)
			(primitives
				(gr_poly
					(pts
						(arc
							(start 0.3048 0.2032)
							(mid 0.275042 0.275042)
							(end 0.2032 0.3048)
						)
						(arc
							(start -0.2032 0.3048)
							(mid -0.275042 0.275042)
							(end -0.3048 0.2032)
						)
						(arc
							(start -0.3048 -0.2032)
							(mid -0.275042 -0.275042)
							(end -0.2032 -0.3048)
						)
						(arc
							(start 0.2032 -0.3048)
							(mid 0.275042 -0.275042)
							(end 0.3048 -0.2032)
						)
					)
					(width 0)
					(fill yes)
				)
			)
		)
		(pad "2" smd custom
			(at 0 0.4445 270)
			(size 0.1524 0.1524)
			(layers "B.Cu" "B.Mask" "B.Paste")
			(net "GND")
			(options
				(clearance outline)
				(anchor circle)
			)
			(primitives
				(gr_poly
					(pts
						(arc
							(start 0.3048 0.2032)
							(mid 0.275042 0.275042)
							(end 0.2032 0.3048)
						)
						(arc
							(start -0.2032 0.3048)
							(mid -0.275042 0.275042)
							(end -0.3048 0.2032)
						)
						(arc
							(start -0.3048 -0.2032)
							(mid -0.275042 -0.275042)
							(end -0.2032 -0.3048)
						)
						(arc
							(start 0.2032 -0.3048)
							(mid 0.275042 -0.275042)
							(end 0.3048 -0.2032)
						)
					)
					(width 0)
					(fill yes)
				)
			)
		)
	)
	(footprint ""
		(layer "B.Cu")
		(at 186.618626 -122.236738 -90)
		(property "Reference" "PSP1"
			(at 0 0 90)
			(layer "B.SilkS")
			(hide yes)
			(effects
				(font
					(size 1.27 1.27)
				)
				(justify mirror)
			)
		)
		(property "Value" "COPPER-CLOSE-GP-U"
			(at -0.0762 -2.8702 270)
			(unlocked yes)
			(layer "B.Fab")
			(hide yes)
			(effects
				(font
					(size 1.016 1.016)
					(thickness 0.1524)
				)
				(justify mirror)
			)
		)
		(property "Device Type" "CON2C-U"
			(at -0.0762 -4.3942 270)
			(unlocked yes)
			(layer "B.Fab")
			(hide yes)
			(effects
				(font
					(size 1.016 1.016)
					(thickness 0.1524)
				)
				(justify mirror)
			)
		)
		(duplicate_pad_numbers_are_jumpers no)
		(fp_rect
			(start 0.9398 0.9652)
			(end -0.9398 -0.9652)
			(stroke
				(width 0)
				(type default)
			)
			(fill no)
			(layer "B.CrtYd")
		)
		(fp_rect
			(start 0.9398 0.9652)
			(end -0.9398 -0.9652)
			(stroke
				(width 0)
				(type default)
			)
			(fill no)
			(layer "B.Fab")
		)
		(pad "1" smd custom
			(at 0 -0.5334 90)
			(size 0.17145 0.17145)
			(layers "B.Cu" "B.Mask" "B.Paste")
			(net "GND")
			(options
				(clearance outline)
				(anchor circle)
			)
			(primitives
				(gr_poly
					(pts
						(xy -0.127 -0.3429) (xy -0.127 -0.1651) (xy -0.635 0.3429) (xy 0.635 0.3429) (xy 0.127 -0.1651)
						(xy 0.127 -0.3429)
					)
					(width 0)
					(fill yes)
				)
			)
		)
		(pad "2" smd custom
			(at 0 0.5334 90)
			(size 0.17145 0.17145)
			(layers "B.Cu" "B.Mask" "B.Paste")
			(net "AGND_P0V975")
			(options
				(clearance outline)
				(anchor circle)
			)
			(primitives
				(gr_poly
					(pts
						(xy -0.635 -0.3429) (xy -0.127 0.1651) (xy -0.127 0.3429) (xy 0.127 0.3429) (xy 0.127 0.1651)
						(xy 0.635 -0.3429)
					)
					(width 0)
					(fill yes)
				)
			)
		)
	)
	(footprint ""
		(layer "B.Cu")
		(at 48.079406 -147.98675 90)
		(property "Reference" "C107"
			(at 0 0 90)
			(layer "B.SilkS")
			(hide yes)
			(effects
				(font
					(size 1.27 1.27)
				)
				(justify mirror)
			)
		)
		(property "Value" "SC1U16V3KX-5GP"
			(at 0 -2.8194 90)
			(unlocked yes)
			(layer "B.Fab")
			(hide yes)
			(effects
				(font
					(size 1.016 1.016)
					(thickness 0.1524)
				)
				(justify mirror)
			)
		)
		(property "Device Type" "C603H36"
			(at 0 -4.3434 90)
			(unlocked yes)
			(layer "B.Fab")
			(hide yes)
			(effects
				(font
					(size 1.016 1.016)
					(thickness 0.1524)
				)
				(justify mirror)
			)
		)
		(duplicate_pad_numbers_are_jumpers no)
		(fp_line
			(start -0.508 0)
			(end 0.508 0)
			(stroke
				(width 0.2032)
				(type default)
			)
			(layer "B.SilkS")
		)
		(fp_rect
			(start 0.5842 1.3335)
			(end -0.5842 -1.3335)
			(stroke
				(width 0)
				(type default)
			)
			(fill no)
			(layer "B.CrtYd")
		)
		(fp_rect
			(start 0.5842 1.3335)
			(end -0.5842 -1.3335)
			(stroke
				(width 0)
				(type default)
			)
			(fill no)
			(layer "B.Fab")
		)
		(pad "1" smd custom
			(at 0 -0.762 270)
			(size 0.2159 0.2159)
			(layers "B.Cu" "B.Mask" "B.Paste")
			(net "P1V15_STBY")
			(options
				(clearance outline)
				(anchor circle)
			)
			(primitives
				(gr_poly
					(pts
						(arc
							(start -0.3302 0.4318)
							(mid -0.402042 0.402042)
							(end -0.4318 0.3302)
						)
						(arc
							(start -0.4318 -0.3302)
							(mid -0.402042 -0.402042)
							(end -0.3302 -0.4318)
						)
						(arc
							(start 0.3302 -0.4318)
							(mid 0.402042 -0.402042)
							(end 0.4318 -0.3302)
						)
						(arc
							(start 0.4318 0.3302)
							(mid 0.402042 0.402042)
							(end 0.3302 0.4318)
						)
					)
					(width 0)
					(fill yes)
				)
			)
		)
		(pad "2" smd custom
			(at 0 0.762 270)
			(size 0.2159 0.2159)
			(layers "B.Cu" "B.Mask" "B.Paste")
			(net "GND")
			(options
				(clearance outline)
				(anchor circle)
			)
			(primitives
				(gr_poly
					(pts
						(arc
							(start -0.3302 0.4318)
							(mid -0.402042 0.402042)
							(end -0.4318 0.3302)
						)
						(arc
							(start -0.4318 -0.3302)
							(mid -0.402042 -0.402042)
							(end -0.3302 -0.4318)
						)
						(arc
							(start 0.3302 -0.4318)
							(mid 0.402042 -0.402042)
							(end 0.4318 -0.3302)
						)
						(arc
							(start 0.4318 0.3302)
							(mid 0.402042 0.402042)
							(end 0.3302 0.4318)
						)
					)
					(width 0)
					(fill yes)
				)
			)
		)
	)
)
